# SCM (Grand Teton) — schematic netlist excerpt (pin names and nets, part order shuffled) for the footprints in the layout excerpt that follows; sources: Cadence DE-HDL packaged netlist, KiCad conversion of 12092022_DA0F0TMDCD0_F0T_Management_Board_D_brd_V3_OCP.brd

C187  Q_CAP  0.1UF 25V 10% X7R  pkg 0402  page 41 : A = VCCIO2 ; B = GND
R210  Q_RES  1K 1% CHIP  pkg 0402LF  page 15 : A = GND ; B = PD_SP_ENTEST
DM7  ME_DUMMY_SYMBOL  PB-E1_SMALL EMPTY  pkg PB-E1_SMALL  page 59

(kicad_pcb
	(version 20260206)
	(generator "pcbnew")
	(generator_version "10.0")
	(general
		(thickness 1.6)
		(legacy_teardrops no)
	)
	(paper "A4")
	(title_block
		(title "12092022_DA0F0TMDCD0_F0T_Management_Board_D_brd_V3_OCP.brd")
		(comment 1 "Grand Teton / footprints 825-827 of 1440")
	)
	(layers
		(0 "F.Cu" signal "TOP")
		(4 "In1.Cu" signal "GND")
		(6 "In2.Cu" signal "IN1")
		(8 "In3.Cu" signal "GND1")
		(10 "In4.Cu" signal "IN2")
		(12 "In5.Cu" signal "VCC")
		(14 "In6.Cu" signal "VCC1")
		(16 "In7.Cu" signal "IN3")
		(18 "In8.Cu" signal "GND2")
		(20 "In9.Cu" signal "IN4")
		(22 "In10.Cu" signal "GND3")
		(2 "B.Cu" signal "BOTTOM")
		(9 "F.Adhes" user "F.Adhesive")
		(11 "B.Adhes" user "B.Adhesive")
		(13 "F.Paste" user "Package Geometry/Pastemask Top")
		(15 "B.Paste" user "Package Geometry/Pastemask Bottom")
		(5 "F.SilkS" user "Ref Des/Silkscreen Top")
		(7 "B.SilkS" user "Ref Des/Silkscreen Bottom")
		(1 "F.Mask" user "Board Geometry/Soldermask Top")
		(3 "B.Mask" user "Board Geometry/Soldermask Bottom")
		(17 "Dwgs.User" user "User.Drawings")
		(19 "Cmts.User" user "User.Comments")
		(21 "Eco1.User" user "User.Eco1")
		(23 "Eco2.User" user "User.Eco2")
		(25 "Edge.Cuts" user "Board Geometry/Outline")
		(27 "Margin" user)
		(31 "F.CrtYd" user "Package Geometry/Place Bound Top")
		(29 "B.CrtYd" user "Package Geometry/Place Bound Bottom")
		(35 "F.Fab" user "Ref Des/Assembly Top")
		(33 "B.Fab" user "Ref Des/Assembly Bottom")
	)
	(footprint ""
		(layer "B.Cu")
		(at 64.102996 -34.637726 -90)
		(property "Reference" "R210"
			(at 0 0 90)
			(layer "B.SilkS")
			(hide yes)
			(effects
				(font
					(size 1.27 1.27)
				)
				(justify mirror)
			)
		)
		(property "Value" ""
			(at 0 0 90)
			(layer "B.Fab")
			(effects
				(font
					(size 1.27 1.27)
				)
				(justify mirror)
			)
		)
		(duplicate_pad_numbers_are_jumpers no)
		(fp_line
			(start -0.7874 0.4064)
			(end 0.7874 0.4064)
			(stroke
				(width 0.1524)
				(type default)
			)
			(layer "B.SilkS")
		)
		(fp_line
			(start 0.7874 0.4064)
			(end 0.7874 -0.4064)
			(stroke
				(width 0.1524)
				(type default)
			)
			(layer "B.SilkS")
		)
		(fp_line
			(start -0.7874 -0.4064)
			(end -0.7874 0.4064)
			(stroke
				(width 0.1524)
				(type default)
			)
			(layer "B.SilkS")
		)
		(fp_line
			(start 0.7874 -0.4064)
			(end -0.7874 -0.4064)
			(stroke
				(width 0.1524)
				(type default)
			)
			(layer "B.SilkS")
		)
		(fp_line
			(start -0.67945 0.3048)
			(end -0.120396 0.3048)
			(stroke
				(width 0.1)
				(type default)
			)
			(layer "B.Fab")
		)
		(fp_line
			(start -0.120396 0.3048)
			(end -0.120396 0.2794)
			(stroke
				(width 0.1)
				(type default)
			)
			(layer "B.Fab")
		)
		(fp_line
			(start 0.12065 0.3048)
			(end 0.67945 0.3048)
			(stroke
				(width 0.1)
				(type default)
			)
			(layer "B.Fab")
		)
		(fp_line
			(start 0.67945 0.3048)
			(end 0.67945 -0.305054)
			(stroke
				(width 0.1)
				(type default)
			)
			(layer "B.Fab")
		)
		(fp_line
			(start -0.120396 0.2794)
			(end 0.12065 0.2794)
			(stroke
				(width 0.1)
				(type default)
			)
			(layer "B.Fab")
		)
		(fp_line
			(start 0.12065 0.2794)
			(end 0.12065 0.3048)
			(stroke
				(width 0.1)
				(type default)
			)
			(layer "B.Fab")
		)
		(fp_line
			(start -0.12065 -0.2794)
			(end -0.12065 -0.3048)
			(stroke
				(width 0.1)
				(type default)
			)
			(layer "B.Fab")
		)
		(fp_line
			(start 0.12065 -0.2794)
			(end -0.12065 -0.2794)
			(stroke
				(width 0.1)
				(type default)
			)
			(layer "B.Fab")
		)
		(fp_line
			(start -0.67945 -0.3048)
			(end -0.67945 0.3048)
			(stroke
				(width 0.1)
				(type default)
			)
			(layer "B.Fab")
		)
		(fp_line
			(start -0.12065 -0.3048)
			(end -0.67945 -0.3048)
			(stroke
				(width 0.1)
				(type default)
			)
			(layer "B.Fab")
		)
		(fp_line
			(start 0.12065 -0.305054)
			(end 0.12065 -0.2794)
			(stroke
				(width 0.1)
				(type default)
			)
			(layer "B.Fab")
		)
		(fp_line
			(start 0.67945 -0.305054)
			(end 0.12065 -0.305054)
			(stroke
				(width 0.1)
				(type default)
			)
			(layer "B.Fab")
		)
		(pad "1" smd circle
			(at 0.40005 0 90)
			(size 0 0)
			(layers "B.Cu" "B.Mask" "B.Paste")
			(net "GND")
		)
		(pad "2" smd circle
			(at -0.40005 0 90)
			(size 0 0)
			(layers "B.Cu" "B.Mask" "B.Paste")
			(net "PD_SP_ENTEST")
		)
	)
	(footprint ""
		(layer "B.Cu")
		(at 84.9122 -67.691)
		(property "Reference" "DM7"
			(at 0 0 0)
			(layer "B.SilkS")
			(hide yes)
			(effects
				(font
					(size 1.27 1.27)
				)
				(justify mirror)
			)
		)
		(property "Value" ""
			(at 0 0 0)
			(layer "B.Fab")
			(effects
				(font
					(size 1.27 1.27)
				)
				(justify mirror)
			)
		)
		(duplicate_pad_numbers_are_jumpers no)
	)
	(footprint ""
		(layer "B.Cu")
		(at 21.859494 -95.187008 90)
		(property "Reference" "C187"
			(at 0 0 90)
			(layer "B.SilkS")
			(hide yes)
			(effects
				(font
					(size 1.27 1.27)
				)
				(justify mirror)
			)
		)
		(property "Value" ""
			(at 0 0 90)
			(layer "B.Fab")
			(effects
				(font
					(size 1.27 1.27)
				)
				(justify mirror)
			)
		)
		(duplicate_pad_numbers_are_jumpers no)
		(fp_line
			(start 0.69215 -0.2921)
			(end -0.69215 -0.2921)
			(stroke
				(width 0.1524)
				(type default)
			)
			(layer "B.SilkS")
		)
		(fp_line
			(start -0.69215 -0.2921)
			(end -0.69215 0.2921)
			(stroke
				(width 0.1524)
				(type default)
			)
			(layer "B.SilkS")
		)
		(fp_line
			(start 0.69215 0.2921)
			(end 0.69215 -0.2921)
			(stroke
				(width 0.1524)
				(type default)
			)
			(layer "B.SilkS")
		)
		(fp_line
			(start -0.69215 0.2921)
			(end 0.69215 0.2921)
			(stroke
				(width 0.1524)
				(type default)
			)
			(layer "B.SilkS")
		)
		(fp_line
			(start 0.51435 -0.2794)
			(end -0.51435 -0.2794)
			(stroke
				(width 0.1)
				(type default)
			)
			(layer "B.Fab")
		)
		(fp_line
			(start -0.51435 -0.2794)
			(end -0.51435 0.2794)
			(stroke
				(width 0.1)
				(type default)
			)
			(layer "B.Fab")
		)
		(fp_line
			(start 0.51435 0.2794)
			(end 0.51435 -0.2794)
			(stroke
				(width 0.1)
				(type default)
			)
			(layer "B.Fab")
		)
		(fp_line
			(start -0.51435 0.2794)
			(end 0.51435 0.2794)
			(stroke
				(width 0.1)
				(type default)
			)
			(layer "B.Fab")
		)
		(pad "1" smd circle
			(at 0.40005 0 270)
			(size 0 0)
			(layers "B.Cu" "B.Mask" "B.Paste")
			(net "VCCIO2")
		)
		(pad "2" smd circle
			(at -0.40005 0 270)
			(size 0 0)
			(layers "B.Cu" "B.Mask" "B.Paste")
			(net "GND")
		)
		(zone
			(layer "B.Cu")
			(hatch none 0.5)
			(connect_pads
				(clearance 0)
			)
			(min_thickness 0.25)
			(keepout
				(tracks not_allowed)
				(vias allowed)
				(pads allowed)
				(copperpour not_allowed)
				(footprints allowed)
			)
			(placement
				(enabled no)
				(sheetname "")
			)
			(fill
				(thermal_gap 0.5)
				(thermal_bridge_width 0.5)
				(island_removal_mode 0)
			)
			(polygon
				(pts
					(xy 21.947124 -95.377508) (xy 22.00529 -95.286068) (xy 22.00529 -95.086678) (xy 21.947124 -94.996508)
					(xy 21.771864 -94.996508) (xy 21.713444 -95.086678) (xy 21.713444 -95.286068) (xy 21.77161 -95.377508)
				)
			)
		)
	)
)
